# SDI-MIPI Bridge — assets/stackup.csv
Name;Type;Material;Thickness[mm];Constant
F.Mask;Top Solder Mask;;0.02;
F.Cu;copper;;0.018;
dielectric 1;prepreg;FR4;0.24;4.2
In1.Cu;copper;;0.035;
dielectric 2;core;FR4;0.36;4.2
In2.Cu;copper;;0.035;
dielectric 3;prepreg;FR4;0.24;4.2
In3.Cu;copper;;0.035;
dielectric 4;core;FR4;0.36;4.5
In4.Cu;copper;;0.035;
dielectric 5;prepreg;FR4;0.24;4.2
B.Cu;copper;;0.018;
B.Mask;Bottom Solder Mask;;0.02;
